# T6G (Grand Teton) — schematic netlist excerpt (pin names and nets, part order shuffled) for the footprints in the layout excerpt that follows; sources: Cadence DE-HDL packaged netlist, KiCad conversion of 04192023_DAF0TMB3IC0_F0TG_MB_C_brd_V02_OCP.brd

C487  Q_CAP  22UF 4V 20% X6S  pkg C0402  page 356 : A = P0V9_CPU1_RT3_2A ; B = GND
C3890  Q_CAP  22UF 4V 20% X6S  pkg C0402  page 68 : A = PVDD11_S3_P0 ; B = GND

(kicad_pcb
	(version 20260206)
	(generator "pcbnew")
	(generator_version "10.0")
	(general
		(thickness 1.6)
		(legacy_teardrops no)
	)
	(paper "A4")
	(title_block
		(title "04192023_DAF0TMB3IC0_F0TG_MB_C_brd_V02_OCP.brd")
		(comment 1 "Grand Teton / footprints 5940-5941 of 8354")
	)
	(layers
		(0 "F.Cu" signal "TOP")
		(4 "In1.Cu" signal "GND")
		(6 "In2.Cu" signal "IN1")
		(8 "In3.Cu" signal "GND1")
		(10 "In4.Cu" signal "IN2")
		(12 "In5.Cu" signal "GND2")
		(14 "In6.Cu" signal "IN3")
		(16 "In7.Cu" signal "GND3")
		(18 "In8.Cu" signal "VCC")
		(20 "In9.Cu" signal "VCC1")
		(22 "In10.Cu" signal "GND4")
		(24 "In11.Cu" signal "IN4")
		(26 "In12.Cu" signal "GND5")
		(28 "In13.Cu" signal "IN5")
		(30 "In14.Cu" signal "GND6")
		(32 "In15.Cu" signal "IN6")
		(34 "In16.Cu" signal "GND7")
		(2 "B.Cu" signal "BOTTOM")
		(9 "F.Adhes" user "F.Adhesive")
		(11 "B.Adhes" user "B.Adhesive")
		(13 "F.Paste" user "Package Geometry/Pastemask Top")
		(15 "B.Paste" user "Package Geometry/Pastemask Bottom")
		(5 "F.SilkS" user "Ref Des/Silkscreen Top")
		(7 "B.SilkS" user "Ref Des/Silkscreen Bottom")
		(1 "F.Mask" user "Board Geometry/Soldermask Top")
		(3 "B.Mask" user "Board Geometry/Soldermask Bottom")
		(17 "Dwgs.User" user "User.Drawings")
		(19 "Cmts.User" user "User.Comments")
		(21 "Eco1.User" user "User.Eco1")
		(23 "Eco2.User" user "User.Eco2")
		(25 "Edge.Cuts" user "Board Geometry/Outline")
		(27 "Margin" user)
		(31 "F.CrtYd" user "Package Geometry/Place Bound Top")
		(29 "B.CrtYd" user "Package Geometry/Place Bound Bottom")
		(35 "F.Fab" user "Ref Des/Assembly Top")
		(33 "B.Fab" user "Ref Des/Assembly Bottom")
	)
	(footprint ""
		(layer "B.Cu")
		(at 356.311454 -266.00531)
		(property "Reference" "C3890"
			(at 0 0 0)
			(layer "B.SilkS")
			(hide yes)
			(effects
				(font
					(size 1.27 1.27)
				)
				(justify mirror)
			)
		)
		(property "Value" ""
			(at 0 0 0)
			(layer "B.Fab")
			(effects
				(font
					(size 1.27 1.27)
				)
				(justify mirror)
			)
		)
		(duplicate_pad_numbers_are_jumpers no)
		(fp_line
			(start -0.7874 -0.4064)
			(end -0.7874 0.4064)
			(stroke
				(width 0.1524)
				(type default)
			)
			(layer "B.SilkS")
		)
		(fp_line
			(start -0.7874 0.4064)
			(end 0.7874 0.4064)
			(stroke
				(width 0.1524)
				(type default)
			)
			(layer "B.SilkS")
		)
		(fp_line
			(start 0.7874 -0.4064)
			(end -0.7874 -0.4064)
			(stroke
				(width 0.1524)
				(type default)
			)
			(layer "B.SilkS")
		)
		(fp_line
			(start 0.7874 0.4064)
			(end 0.7874 -0.4064)
			(stroke
				(width 0.1524)
				(type default)
			)
			(layer "B.SilkS")
		)
		(fp_line
			(start -0.67945 -0.3048)
			(end -0.67945 0.3048)
			(stroke
				(width 0.1)
				(type default)
			)
			(layer "B.Fab")
		)
		(fp_line
			(start -0.67945 0.3048)
			(end -0.120396 0.3048)
			(stroke
				(width 0.1)
				(type default)
			)
			(layer "B.Fab")
		)
		(fp_line
			(start -0.12065 -0.3048)
			(end -0.67945 -0.3048)
			(stroke
				(width 0.1)
				(type default)
			)
			(layer "B.Fab")
		)
		(fp_line
			(start -0.12065 -0.2794)
			(end -0.12065 -0.3048)
			(stroke
				(width 0.1)
				(type default)
			)
			(layer "B.Fab")
		)
		(fp_line
			(start -0.120396 0.2794)
			(end 0.12065 0.2794)
			(stroke
				(width 0.1)
				(type default)
			)
			(layer "B.Fab")
		)
		(fp_line
			(start -0.120396 0.3048)
			(end -0.120396 0.2794)
			(stroke
				(width 0.1)
				(type default)
			)
			(layer "B.Fab")
		)
		(fp_line
			(start 0.12065 -0.305054)
			(end 0.12065 -0.2794)
			(stroke
				(width 0.1)
				(type default)
			)
			(layer "B.Fab")
		)
		(fp_line
			(start 0.12065 -0.2794)
			(end -0.12065 -0.2794)
			(stroke
				(width 0.1)
				(type default)
			)
			(layer "B.Fab")
		)
		(fp_line
			(start 0.12065 0.2794)
			(end 0.12065 0.3048)
			(stroke
				(width 0.1)
				(type default)
			)
			(layer "B.Fab")
		)
		(fp_line
			(start 0.12065 0.3048)
			(end 0.67945 0.3048)
			(stroke
				(width 0.1)
				(type default)
			)
			(layer "B.Fab")
		)
		(fp_line
			(start 0.67945 -0.305054)
			(end 0.12065 -0.305054)
			(stroke
				(width 0.1)
				(type default)
			)
			(layer "B.Fab")
		)
		(fp_line
			(start 0.67945 0.3048)
			(end 0.67945 -0.305054)
			(stroke
				(width 0.1)
				(type default)
			)
			(layer "B.Fab")
		)
		(pad "1" smd circle
			(at 0.40005 0 180)
			(size 0 0)
			(layers "B.Cu" "B.Mask" "B.Paste")
			(net "PVDD11_S3_P0")
		)
		(pad "2" smd circle
			(at -0.40005 0 180)
			(size 0 0)
			(layers "B.Cu" "B.Mask" "B.Paste")
			(net "GND")
		)
	)
	(footprint ""
		(layer "B.Cu")
		(at 119.291354 -390.560052 90)
		(property "Reference" "C487"
			(at 0 0 90)
			(layer "B.SilkS")
			(hide yes)
			(effects
				(font
					(size 1.27 1.27)
				)
				(justify mirror)
			)
		)
		(property "Value" ""
			(at 0 0 90)
			(layer "B.Fab")
			(effects
				(font
					(size 1.27 1.27)
				)
				(justify mirror)
			)
		)
		(duplicate_pad_numbers_are_jumpers no)
		(fp_line
			(start 0.7874 -0.4064)
			(end -0.7874 -0.4064)
			(stroke
				(width 0.1524)
				(type default)
			)
			(layer "B.SilkS")
		)
		(fp_line
			(start -0.7874 -0.4064)
			(end -0.7874 0.4064)
			(stroke
				(width 0.1524)
				(type default)
			)
			(layer "B.SilkS")
		)
		(fp_line
			(start 0.7874 0.4064)
			(end 0.7874 -0.4064)
			(stroke
				(width 0.1524)
				(type default)
			)
			(layer "B.SilkS")
		)
		(fp_line
			(start -0.7874 0.4064)
			(end 0.7874 0.4064)
			(stroke
				(width 0.1524)
				(type default)
			)
			(layer "B.SilkS")
		)
		(fp_line
			(start 0.67945 -0.305054)
			(end 0.12065 -0.305054)
			(stroke
				(width 0.1)
				(type default)
			)
			(layer "B.Fab")
		)
		(fp_line
			(start 0.12065 -0.305054)
			(end 0.12065 -0.2794)
			(stroke
				(width 0.1)
				(type default)
			)
			(layer "B.Fab")
		)
		(fp_line
			(start -0.12065 -0.3048)
			(end -0.67945 -0.3048)
			(stroke
				(width 0.1)
				(type default)
			)
			(layer "B.Fab")
		)
		(fp_line
			(start -0.67945 -0.3048)
			(end -0.67945 0.3048)
			(stroke
				(width 0.1)
				(type default)
			)
			(layer "B.Fab")
		)
		(fp_line
			(start 0.12065 -0.2794)
			(end -0.12065 -0.2794)
			(stroke
				(width 0.1)
				(type default)
			)
			(layer "B.Fab")
		)
		(fp_line
			(start -0.12065 -0.2794)
			(end -0.12065 -0.3048)
			(stroke
				(width 0.1)
				(type default)
			)
			(layer "B.Fab")
		)
		(fp_line
			(start 0.12065 0.2794)
			(end 0.12065 0.3048)
			(stroke
				(width 0.1)
				(type default)
			)
			(layer "B.Fab")
		)
		(fp_line
			(start -0.120396 0.2794)
			(end 0.12065 0.2794)
			(stroke
				(width 0.1)
				(type default)
			)
			(layer "B.Fab")
		)
		(fp_line
			(start 0.67945 0.3048)
			(end 0.67945 -0.305054)
			(stroke
				(width 0.1)
				(type default)
			)
			(layer "B.Fab")
		)
		(fp_line
			(start 0.12065 0.3048)
			(end 0.67945 0.3048)
			(stroke
				(width 0.1)
				(type default)
			)
			(layer "B.Fab")
		)
		(fp_line
			(start -0.120396 0.3048)
			(end -0.120396 0.2794)
			(stroke
				(width 0.1)
				(type default)
			)
			(layer "B.Fab")
		)
		(fp_line
			(start -0.67945 0.3048)
			(end -0.120396 0.3048)
			(stroke
				(width 0.1)
				(type default)
			)
			(layer "B.Fab")
		)
		(pad "1" smd circle
			(at 0.40005 0 270)
			(size 0 0)
			(layers "B.Cu" "B.Mask" "B.Paste")
			(net "P0V9_CPU1_RT3_2A")
		)
		(pad "2" smd circle
			(at -0.40005 0 270)
			(size 0 0)
			(layers "B.Cu" "B.Mask" "B.Paste")
			(net "GND")
		)
	)
)
